# BASEBOARD_FAB2 (Tioga Pass) — schematic netlist excerpt (pin names and nets, part order shuffled) for the footprints in the layout excerpt that follows; sources: Cadence DE-HDL packaged netlist, KiCad conversion of Wiwynn_Tioga_Pass_MB.brd

R4B14  RES  0.0 5% CHIP  pkg 0402  page 234 : A = GND ; B = AGND_PVPP_KLM
R2T1  RES  1.00K 1% EMPTY  pkg 0402  page 125 : A = SPI_PCH_IO3 ; B = GND
CR1B2  DIODE  SDMK0340L IC  pkg SM  page 161 : C = FAN_TACH2_CPU1_D1 ; A = FAN_TACH2_CPU1_D2

(kicad_pcb
	(version 20260206)
	(generator "pcbnew")
	(generator_version "10.0")
	(general
		(thickness 1.6)
		(legacy_teardrops no)
	)
	(paper "A4")
	(title_block
		(title "Wiwynn_Tioga_Pass_MB.brd")
		(comment 1 "Tioga Pass / footprints 1448-1450 of 4770")
	)
	(layers
		(0 "F.Cu" signal "TOP")
		(4 "In1.Cu" signal "L2GND")
		(6 "In2.Cu" signal "L3")
		(8 "In3.Cu" signal "L4GND")
		(10 "In4.Cu" signal "L5")
		(12 "In5.Cu" signal "L6GND")
		(14 "In6.Cu" signal "L7VCC")
		(16 "In7.Cu" signal "L8VCC")
		(18 "In8.Cu" signal "L9GND")
		(20 "In9.Cu" signal "L10")
		(22 "In10.Cu" signal "L11GND")
		(24 "In11.Cu" signal "L12")
		(26 "In12.Cu" signal "L13GND")
		(2 "B.Cu" signal "BOTTOM")
		(9 "F.Adhes" user "F.Adhesive")
		(11 "B.Adhes" user "B.Adhesive")
		(13 "F.Paste" user "Package Geometry/Pastemask Top")
		(15 "B.Paste" user "Package Geometry/Pastemask Bottom")
		(5 "F.SilkS" user "Ref Des/Silkscreen Top")
		(7 "B.SilkS" user "Ref Des/Silkscreen Bottom")
		(1 "F.Mask" user "Board Geometry/Soldermask Top")
		(3 "B.Mask" user "Board Geometry/Soldermask Bottom")
		(17 "Dwgs.User" user "User.Drawings")
		(19 "Cmts.User" user "User.Comments")
		(21 "Eco1.User" user "User.Eco1")
		(23 "Eco2.User" user "User.Eco2")
		(25 "Edge.Cuts" user "Board Geometry/Outline")
		(27 "Margin" user)
		(31 "F.CrtYd" user "Package Geometry/Place Bound Top")
		(29 "B.CrtYd" user "Package Geometry/Place Bound Bottom")
		(35 "F.Fab" user "Ref Des/Assembly Top")
		(33 "B.Fab" user "Ref Des/Assembly Bottom")
	)
	(footprint ""
		(layer "F.Cu")
		(at 21.80971 -119.62765 -90)
		(property "Reference" "CR1B2"
			(at 2.58699 1.60528 0)
			(unlocked yes)
			(layer "F.SilkS")
			(effects
				(font
					(size 0.7874 0.5842)
					(thickness 0.1524)
				)
				(justify left)
			)
		)
		(property "Value" ""
			(at 0 0 270)
			(layer "F.Fab")
			(effects
				(font
					(size 1.27 1.27)
				)
			)
		)
		(duplicate_pad_numbers_are_jumpers no)
		(fp_line
			(start -0.931418 2.543048)
			(end -0.931418 1.631442)
			(stroke
				(width 0.1524)
				(type default)
			)
			(layer "F.SilkS")
		)
		(fp_line
			(start -1.41224 1.631442)
			(end -0.931418 0.798576)
			(stroke
				(width 0.1524)
				(type default)
			)
			(layer "F.SilkS")
		)
		(fp_line
			(start -0.931418 1.631442)
			(end -1.41224 1.631442)
			(stroke
				(width 0.1524)
				(type default)
			)
			(layer "F.SilkS")
		)
		(fp_line
			(start -0.450596 1.631442)
			(end -0.931418 1.631442)
			(stroke
				(width 0.1524)
				(type default)
			)
			(layer "F.SilkS")
		)
		(fp_line
			(start -0.931418 0.798576)
			(end -0.450596 1.631442)
			(stroke
				(width 0.1524)
				(type default)
			)
			(layer "F.SilkS")
		)
		(fp_line
			(start -0.450596 0.798576)
			(end -1.41224 0.798576)
			(stroke
				(width 0.1524)
				(type default)
			)
			(layer "F.SilkS")
		)
		(fp_line
			(start -0.931418 -0.324866)
			(end -0.931418 0.798576)
			(stroke
				(width 0.1524)
				(type default)
			)
			(layer "F.SilkS")
		)
		(fp_rect
			(start 0.67437 2.04216)
			(end -0.67437 0.24384)
			(stroke
				(width 0)
				(type default)
			)
			(fill no)
			(layer "F.CrtYd")
		)
		(fp_line
			(start -0.67437 2.04216)
			(end 0.67437 2.04216)
			(stroke
				(width 0.1)
				(type default)
			)
			(layer "F.Fab")
		)
		(fp_line
			(start 0.67437 2.04216)
			(end 0.67437 0.24384)
			(stroke
				(width 0.1)
				(type default)
			)
			(layer "F.Fab")
		)
		(fp_line
			(start -1.412748 1.621536)
			(end -0.931926 0.78867)
			(stroke
				(width 0.1)
				(type default)
			)
			(layer "F.Fab")
		)
		(fp_line
			(start -0.931926 1.621536)
			(end -0.931926 2.533142)
			(stroke
				(width 0.1)
				(type default)
			)
			(layer "F.Fab")
		)
		(fp_line
			(start -0.451104 1.621536)
			(end -1.412748 1.621536)
			(stroke
				(width 0.1)
				(type default)
			)
			(layer "F.Fab")
		)
		(fp_line
			(start -0.931926 0.78867)
			(end -0.451104 1.621536)
			(stroke
				(width 0.1)
				(type default)
			)
			(layer "F.Fab")
		)
		(fp_line
			(start -0.931926 0.78867)
			(end -0.931926 -0.334772)
			(stroke
				(width 0.1)
				(type default)
			)
			(layer "F.Fab")
		)
		(fp_line
			(start -0.451104 0.78867)
			(end -1.412748 0.78867)
			(stroke
				(width 0.1)
				(type default)
			)
			(layer "F.Fab")
		)
		(fp_line
			(start -0.67437 0.24384)
			(end -0.67437 2.04216)
			(stroke
				(width 0.1)
				(type default)
			)
			(layer "F.Fab")
		)
		(fp_line
			(start 0.67437 0.24384)
			(end -0.67437 0.24384)
			(stroke
				(width 0.1)
				(type default)
			)
			(layer "F.Fab")
		)
		(pad "1" smd rect
			(at 0 0 270)
			(size 0.4064 1.016)
			(layers "F.Cu" "F.Mask" "F.Paste")
			(net "FAN_TACH2_CPU1_D1")
		)
		(pad "2" smd rect
			(at 0 2.286 270)
			(size 0.4064 1.016)
			(layers "F.Cu" "F.Mask" "F.Paste")
			(net "FAN_TACH2_CPU1_D2")
		)
	)
	(footprint ""
		(layer "F.Cu")
		(at 173.6217 -128.9558 180)
		(property "Reference" "R4B14"
			(at 0 0 180)
			(layer "F.SilkS")
			(hide yes)
			(effects
				(font
					(size 1.27 1.27)
				)
			)
		)
		(property "Value" ""
			(at 0 0 180)
			(layer "F.Fab")
			(effects
				(font
					(size 1.27 1.27)
				)
			)
		)
		(duplicate_pad_numbers_are_jumpers no)
		(fp_rect
			(start -0.2794 0.9906)
			(end 0.2794 -0.1016)
			(stroke
				(width 0)
				(type default)
			)
			(fill no)
			(layer "F.CrtYd")
		)
		(fp_line
			(start 0.2794 0.9906)
			(end 0.2794 -0.1016)
			(stroke
				(width 0.1)
				(type default)
			)
			(layer "F.Fab")
		)
		(fp_line
			(start 0.2794 -0.1016)
			(end -0.2794 -0.1016)
			(stroke
				(width 0.1)
				(type default)
			)
			(layer "F.Fab")
		)
		(fp_line
			(start -0.2794 0.9906)
			(end 0.2794 0.9906)
			(stroke
				(width 0.1)
				(type default)
			)
			(layer "F.Fab")
		)
		(fp_line
			(start -0.2794 -0.1016)
			(end -0.2794 0.9906)
			(stroke
				(width 0.1)
				(type default)
			)
			(layer "F.Fab")
		)
		(pad "1" smd rect
			(at 0 0 180)
			(size 0.508 0.508)
			(layers "F.Cu" "F.Mask" "F.Paste")
			(net "GND")
		)
		(pad "2" smd rect
			(at 0 0.889 180)
			(size 0.508 0.508)
			(layers "F.Cu" "F.Mask" "F.Paste")
			(net "AGND_PVPP_KLM")
		)
		(zone
			(layer "F.Cu")
			(hatch none 0.5)
			(connect_pads
				(clearance 0)
			)
			(min_thickness 0.25)
			(keepout
				(tracks allowed)
				(vias not_allowed)
				(pads allowed)
				(copperpour not_allowed)
				(footprints allowed)
			)
			(placement
				(enabled no)
				(sheetname "")
			)
			(fill
				(thermal_gap 0.5)
				(thermal_bridge_width 0.5)
				(island_removal_mode 0)
			)
			(polygon
				(pts
					(xy 173.8757 -129.5908) (xy 173.3677 -129.5908) (xy 173.3677 -129.2098) (xy 173.8757 -129.2098)
				)
			)
		)
		(zone
			(layer "F.Cu")
			(hatch none 0.5)
			(connect_pads
				(clearance 0)
			)
			(min_thickness 0.25)
			(keepout
				(tracks not_allowed)
				(vias allowed)
				(pads allowed)
				(copperpour not_allowed)
				(footprints allowed)
			)
			(placement
				(enabled no)
				(sheetname "")
			)
			(fill
				(thermal_gap 0.5)
				(thermal_bridge_width 0.5)
				(island_removal_mode 0)
			)
			(polygon
				(pts
					(xy 173.8757 -129.5908) (xy 173.3677 -129.5908) (xy 173.3677 -129.2098) (xy 173.8757 -129.2098)
				)
			)
		)
	)
	(footprint ""
		(layer "F.Cu")
		(at 376.682 -87.3125 180)
		(property "Reference" "R2T1"
			(at -0.8382 -0.67818 180)
			(unlocked yes)
			(layer "F.SilkS")
			(effects
				(font
					(size 0.4064 0.254)
					(thickness 0.1524)
				)
				(justify left)
			)
		)
		(property "Value" ""
			(at 0 0 180)
			(layer "F.Fab")
			(effects
				(font
					(size 1.27 1.27)
				)
			)
		)
		(duplicate_pad_numbers_are_jumpers no)
		(fp_poly
			(pts
				(xy -0.2794 -0.1016) (xy 0.2794 -0.1016) (xy 0.2794 0.9906) (xy -0.2794 0.9906)
			)
			(stroke
				(width 0)
				(type default)
			)
			(fill no)
			(layer "F.CrtYd")
		)
		(fp_line
			(start 0.2794 0.9906)
			(end 0.2794 -0.1016)
			(stroke
				(width 0.1)
				(type default)
			)
			(layer "F.Fab")
		)
		(fp_line
			(start 0.2794 -0.1016)
			(end -0.2794 -0.1016)
			(stroke
				(width 0.1)
				(type default)
			)
			(layer "F.Fab")
		)
		(fp_line
			(start -0.2794 0.9906)
			(end 0.2794 0.9906)
			(stroke
				(width 0.1)
				(type default)
			)
			(layer "F.Fab")
		)
		(fp_line
			(start -0.2794 -0.1016)
			(end -0.2794 0.9906)
			(stroke
				(width 0.1)
				(type default)
			)
			(layer "F.Fab")
		)
		(pad "1" smd rect
			(at 0 0 180)
			(size 0.508 0.508)
			(layers "F.Cu" "F.Mask" "F.Paste")
			(net "SPI_PCH_IO3")
		)
		(pad "2" smd rect
			(at 0 0.889 180)
			(size 0.508 0.508)
			(layers "F.Cu" "F.Mask" "F.Paste")
			(net "GND")
		)
		(zone
			(layer "F.Cu")
			(hatch none 0.5)
			(connect_pads
				(clearance 0)
			)
			(min_thickness 0.25)
			(keepout
				(tracks not_allowed)
				(vias allowed)
				(pads allowed)
				(copperpour not_allowed)
				(footprints allowed)
			)
			(placement
				(enabled no)
				(sheetname "")
			)
			(fill
				(thermal_gap 0.5)
				(thermal_bridge_width 0.5)
				(island_removal_mode 0)
			)
			(polygon
				(pts
					(xy 376.936 -87.9475) (xy 376.428 -87.9475) (xy 376.428 -87.5665) (xy 376.936 -87.5665)
				)
			)
		)
		(zone
			(layer "F.Cu")
			(hatch none 0.5)
			(connect_pads
				(clearance 0)
			)
			(min_thickness 0.25)
			(keepout
				(tracks allowed)
				(vias not_allowed)
				(pads allowed)
				(copperpour not_allowed)
				(footprints allowed)
			)
			(placement
				(enabled no)
				(sheetname "")
			)
			(fill
				(thermal_gap 0.5)
				(thermal_bridge_width 0.5)
				(island_removal_mode 0)
			)
			(polygon
				(pts
					(xy 376.936 -87.5665) (xy 376.428 -87.5665) (xy 376.428 -87.9475) (xy 376.936 -87.9475)
				)
			)
		)
	)
)
